(kicad_pcb
	(version 20241229)
	(generator "pcbnew")
	(generator_version "9.0")
	(general
		(thickness 1.62)
		(legacy_teardrops no)
	)
	(paper "A3")
	(title_block
		(title "COM Express 7 Baseboard")
		(date "2025-02-04")
		(rev "1.1.2")
		(company "Antmicro Ltd")
		(comment 1 "www.antmicro.com")
		(comment 9 "footprints 192-195 of 802")
	)
	(layers
		(0 "F.Cu" signal)
		(4 "In1.Cu" signal)
		(6 "In2.Cu" signal)
		(8 "In3.Cu" signal)
		(10 "In4.Cu" signal)
		(12 "In5.Cu" signal)
		(14 "In6.Cu" signal)
		(2 "B.Cu" signal)
		(9 "F.Adhes" user "F.Adhesive")
		(11 "B.Adhes" user "B.Adhesive")
		(13 "F.Paste" user)
		(15 "B.Paste" user)
		(5 "F.SilkS" user "F.Silkscreen")
		(7 "B.SilkS" user "B.Silkscreen")
		(1 "F.Mask" user)
		(3 "B.Mask" user)
		(17 "Dwgs.User" user "User.Drawings")
		(19 "Cmts.User" user "User.Comments")
		(21 "Eco1.User" user "User.Eco1")
		(23 "Eco2.User" user "User.Eco2")
		(25 "Edge.Cuts" user)
		(27 "Margin" user)
		(31 "F.CrtYd" user "F.Courtyard")
		(29 "B.CrtYd" user "B.Courtyard")
		(35 "F.Fab" user)
		(33 "B.Fab" user)
	)
	(footprint "antmicro-footprints:R_0201"
		(layer "F.Cu")
		(at 132.17 147.336 -90)
		(descr "Resistor SMD 0201")
		(tags "resistor SMD 0201")
		(property "Reference" "R309"
			(at 4.073 -0.58 270)
			(layer "F.SilkS")
			(effects
				(font
					(size 0.7 0.7)
					(thickness 0.15)
				)
				(justify left bottom)
			)
		)
		(property "Value" "R_0R_0201"
			(at 0 1.25 270)
			(layer "F.Fab")
			(effects
				(font
					(size 0.7 0.7)
					(thickness 0.15)
				)
				(justify left bottom)
			)
		)
		(property "Datasheet" "https://www.bourns.com/docs/product-datasheets/cr.pdf"
			(at 0 0 270)
			(layer "F.Fab")
			(hide yes)
			(effects
				(font
					(size 1.27 1.27)
					(thickness 0.15)
				)
			)
		)
		(property "Author" "Antmicro"
			(at -15.166 279.506 0)
			(layer "F.Fab")
			(hide yes)
			(effects
				(font
					(size 1 1)
					(thickness 0.15)
				)
			)
		)
		(property "License" "Apache-2.0"
			(at -15.166 279.506 0)
			(layer "F.Fab")
			(hide yes)
			(effects
				(font
					(size 1 1)
					(thickness 0.15)
				)
			)
		)
		(property "MPN" "CR0201-FX-0R00GLF"
			(at -15.166 279.506 0)
			(layer "F.Fab")
			(hide yes)
			(effects
				(font
					(size 1 1)
					(thickness 0.15)
				)
			)
		)
		(property "Manufacturer" "Bourns"
			(at -15.166 279.506 0)
			(layer "F.Fab")
			(hide yes)
			(effects
				(font
					(size 1 1)
					(thickness 0.15)
				)
			)
		)
		(property "Tolerance" "1%"
			(at -15.166 279.506 0)
			(layer "F.Fab")
			(hide yes)
			(effects
				(font
					(size 1 1)
					(thickness 0.15)
				)
			)
		)
		(property "Val" "0R"
			(at -15.166 279.506 0)
			(layer "F.Fab")
			(hide yes)
			(effects
				(font
					(size 1 1)
					(thickness 0.15)
				)
			)
		)
		(sheetname "KR to SFI #2")
		(sheetfile "kr_sfi.kicad_sch")
		(attr smd)
		(fp_rect
			(start -0.7 -0.35)
			(end 0.7 0.35)
			(stroke
				(width 0.05)
				(type default)
			)
			(fill no)
			(layer "F.CrtYd")
		)
		(fp_rect
			(start -0.3 -0.15)
			(end 0.298 0.148)
			(stroke
				(width 0.15)
				(type solid)
			)
			(fill no)
			(layer "F.Fab")
		)
		(pad "" smd roundrect
			(at -0.346 0 270)
			(size 0.318 0.36)
			(layers "F.Paste")
			(roundrect_rratio 0.25)
			(teardrops
				(best_length_ratio 0.2)
				(max_length 1)
				(best_width_ratio 0.9)
				(max_width 2)
				(curved_edges yes)
				(filter_ratio 0.9)
				(enabled yes)
				(allow_two_segments yes)
				(prefer_zone_connections yes)
			)
		)
		(pad "" smd roundrect
			(at 0.344 0 270)
			(size 0.318 0.36)
			(layers "F.Paste")
			(roundrect_rratio 0.25)
			(teardrops
				(best_length_ratio 0.2)
				(max_length 1)
				(best_width_ratio 0.9)
				(max_width 2)
				(curved_edges yes)
				(filter_ratio 0.9)
				(enabled yes)
				(allow_two_segments yes)
				(prefer_zone_connections yes)
			)
		)
		(pad "1" smd roundrect
			(at -0.32 0 270)
			(size 0.46 0.4)
			(layers "F.Cu" "F.Mask")
			(roundrect_rratio 0.25)
			(net 953 "/2xSFP+/KR to SFI #2/SFI_R.RX-")
			(pintype "passive")
			(teardrops
				(best_length_ratio 0.2)
				(max_length 1)
				(best_width_ratio 0.9)
				(max_width 2)
				(curved_edges yes)
				(filter_ratio 0.9)
				(enabled yes)
				(allow_two_segments yes)
				(prefer_zone_connections yes)
			)
		)
		(pad "2" smd roundrect
			(at 0.32 0 270)
			(size 0.46 0.4)
			(layers "F.Cu" "F.Mask")
			(roundrect_rratio 0.25)
			(net 877 "/2xSFP+/SFI1.RX-")
			(pintype "passive")
			(teardrops
				(best_length_ratio 0.2)
				(max_length 1)
				(best_width_ratio 0.9)
				(max_width 2)
				(curved_edges yes)
				(filter_ratio 0.9)
				(enabled yes)
				(allow_two_segments yes)
				(prefer_zone_connections yes)
			)
		)
	)
	(footprint "antmicro-footprints:C_0402_1005Metric"
		(layer "F.Cu")
		(at 300.64 130.56 90)
		(descr "Capacitor SMD 0402")
		(tags "capacitor SMD 0402")
		(property "Reference" "C54"
			(at -1.1 -0.49 90)
			(layer "F.SilkS")
			(effects
				(font
					(size 0.7 0.7)
					(thickness 0.15)
				)
				(justify left bottom)
			)
		)
		(property "Value" "C_100n_0402"
			(at -1.022927 2.155213 90)
			(layer "F.Fab")
			(effects
				(font
					(size 0.7 0.7)
					(thickness 0.15)
				)
				(justify left bottom)
			)
		)
		(property "Datasheet" "https://www.murata.com/products/productdetail?partno=GRM155R61H104KE14%23"
			(at 0 0 90)
			(layer "F.Fab")
			(hide yes)
			(effects
				(font
					(size 1.27 1.27)
					(thickness 0.15)
				)
			)
		)
		(property "Author" "Antmicro"
			(at 431.2 -170.08 0)
			(layer "F.Fab")
			(hide yes)
			(effects
				(font
					(size 1 1)
					(thickness 0.15)
				)
			)
		)
		(property "Dielectric" "X5R"
			(at 431.2 -170.08 0)
			(layer "F.Fab")
			(hide yes)
			(effects
				(font
					(size 1 1)
					(thickness 0.15)
				)
			)
		)
		(property "License" "Apache-2.0"
			(at 431.2 -170.08 0)
			(layer "F.Fab")
			(hide yes)
			(effects
				(font
					(size 1 1)
					(thickness 0.15)
				)
			)
		)
		(property "MPN" "GRM155R61H104KE14D"
			(at 431.2 -170.08 0)
			(layer "F.Fab")
			(hide yes)
			(effects
				(font
					(size 1 1)
					(thickness 0.15)
				)
			)
		)
		(property "Manufacturer" "Murata"
			(at 431.2 -170.08 0)
			(layer "F.Fab")
			(hide yes)
			(effects
				(font
					(size 1 1)
					(thickness 0.15)
				)
			)
		)
		(property "Public" "False"
			(at 431.2 -170.08 0)
			(layer "F.Fab")
			(hide yes)
			(effects
				(font
					(size 1 1)
					(thickness 0.15)
				)
			)
		)
		(property "Val" "100n"
			(at 431.2 -170.08 0)
			(layer "F.Fab")
			(hide yes)
			(effects
				(font
					(size 1 1)
					(thickness 0.15)
				)
			)
		)
		(property "Voltage" "50V"
			(at 431.2 -170.08 0)
			(layer "F.Fab")
			(hide yes)
			(effects
				(font
					(size 1 1)
					(thickness 0.15)
				)
			)
		)
		(sheetname "Power")
		(sheetfile "power.kicad_sch")
		(attr smd)
		(fp_rect
			(start -0.925 -0.47)
			(end 0.925 0.47)
			(stroke
				(width 0.05)
				(type default)
			)
			(fill no)
			(layer "F.CrtYd")
		)
		(fp_line
			(start 0.504 -0.25)
			(end 0.504 0.248)
			(stroke
				(width 0.15)
				(type solid)
			)
			(layer "F.Fab")
		)
		(fp_line
			(start -0.494 -0.25)
			(end 0.504 -0.25)
			(stroke
				(width 0.15)
				(type solid)
			)
			(layer "F.Fab")
		)
		(fp_line
			(start 0.504 0.248)
			(end -0.494 0.248)
			(stroke
				(width 0.15)
				(type solid)
			)
			(layer "F.Fab")
		)
		(fp_line
			(start -0.494 0.248)
			(end -0.494 -0.25)
			(stroke
				(width 0.15)
				(type solid)
			)
			(layer "F.Fab")
		)
		(pad "1" smd roundrect
			(at -0.48 0 90)
			(size 0.59 0.64)
			(layers "F.Cu" "F.Mask" "F.Paste")
			(roundrect_rratio 0.25)
			(net 1 "GND")
			(pintype "passive")
			(teardrops
				(best_length_ratio 0.2)
				(max_length 1)
				(best_width_ratio 0.9)
				(max_width 2)
				(curved_edges yes)
				(filter_ratio 0.9)
				(enabled yes)
				(allow_two_segments yes)
				(prefer_zone_connections yes)
			)
		)
		(pad "2" smd roundrect
			(at 0.48 0 90)
			(size 0.59 0.64)
			(layers "F.Cu" "F.Mask" "F.Paste")
			(roundrect_rratio 0.25)
			(net 73 "+3V3_AON")
			(pintype "passive")
			(teardrops
				(best_length_ratio 0.2)
				(max_length 1)
				(best_width_ratio 0.9)
				(max_width 2)
				(curved_edges yes)
				(filter_ratio 0.9)
				(enabled yes)
				(allow_two_segments yes)
				(prefer_zone_connections yes)
			)
		)
	)
	(footprint "antmicro-footprints:C_0402_1005Metric"
		(layer "F.Cu")
		(at 114.4 148.421 -90)
		(descr "Capacitor SMD 0402")
		(tags "capacitor SMD 0402")
		(property "Reference" "C111"
			(at -12.611 -2.6 90)
			(layer "F.SilkS")
			(effects
				(font
					(size 0.7 0.7)
					(thickness 0.15)
				)
				(justify right bottom)
			)
		)
		(property "Value" "C_100n_0402"
			(at -1.022927 2.155213 90)
			(layer "F.Fab")
			(effects
				(font
					(size 0.7 0.7)
					(thickness 0.15)
				)
				(justify right bottom)
			)
		)
		(property "Datasheet" "https://www.murata.com/products/productdetail?partno=GRM155R61H104KE14%23"
			(at 0 0 270)
			(layer "F.Fab")
			(hide yes)
			(effects
				(font
					(size 1.27 1.27)
					(thickness 0.15)
				)
			)
		)
		(property "Author" "Antmicro"
			(at -34.021 262.821 0)
			(layer "F.Fab")
			(hide yes)
			(effects
				(font
					(size 1 1)
					(thickness 0.15)
				)
			)
		)
		(property "Dielectric" "X5R"
			(at -34.021 262.821 0)
			(layer "F.Fab")
			(hide yes)
			(effects
				(font
					(size 1 1)
					(thickness 0.15)
				)
			)
		)
		(property "License" "Apache-2.0"
			(at -34.021 262.821 0)
			(layer "F.Fab")
			(hide yes)
			(effects
				(font
					(size 1 1)
					(thickness 0.15)
				)
			)
		)
		(property "MPN" "GRM155R61H104KE14D"
			(at -34.021 262.821 0)
			(layer "F.Fab")
			(hide yes)
			(effects
				(font
					(size 1 1)
					(thickness 0.15)
				)
			)
		)
		(property "Manufacturer" "Murata"
			(at -34.021 262.821 0)
			(layer "F.Fab")
			(hide yes)
			(effects
				(font
					(size 1 1)
					(thickness 0.15)
				)
			)
		)
		(property "Public" "False"
			(at -34.021 262.821 0)
			(layer "F.Fab")
			(hide yes)
			(effects
				(font
					(size 1 1)
					(thickness 0.15)
				)
			)
		)
		(property "Val" "100n"
			(at -34.021 262.821 0)
			(layer "F.Fab")
			(hide yes)
			(effects
				(font
					(size 1 1)
					(thickness 0.15)
				)
			)
		)
		(property "Voltage" "50V"
			(at -34.021 262.821 0)
			(layer "F.Fab")
			(hide yes)
			(effects
				(font
					(size 1 1)
					(thickness 0.15)
				)
			)
		)
		(sheetname "PCIe redriver")
		(sheetfile "pcie_redriver.kicad_sch")
		(attr smd)
		(fp_rect
			(start -0.925 -0.47)
			(end 0.925 0.47)
			(stroke
				(width 0.05)
				(type default)
			)
			(fill no)
			(layer "F.CrtYd")
		)
		(fp_line
			(start -0.494 0.248)
			(end -0.494 -0.25)
			(stroke
				(width 0.15)
				(type solid)
			)
			(layer "F.Fab")
		)
		(fp_line
			(start 0.504 0.248)
			(end -0.494 0.248)
			(stroke
				(width 0.15)
				(type solid)
			)
			(layer "F.Fab")
		)
		(fp_line
			(start -0.494 -0.25)
			(end 0.504 -0.25)
			(stroke
				(width 0.15)
				(type solid)
			)
			(layer "F.Fab")
		)
		(fp_line
			(start 0.504 -0.25)
			(end 0.504 0.248)
			(stroke
				(width 0.15)
				(type solid)
			)
			(layer "F.Fab")
		)
		(pad "1" smd roundrect
			(at -0.48 0 270)
			(size 0.59 0.64)
			(layers "F.Cu" "F.Mask" "F.Paste")
			(roundrect_rratio 0.25)
			(net 1 "GND")
			(pintype "passive")
			(teardrops
				(best_length_ratio 0.2)
				(max_length 1)
				(best_width_ratio 0.9)
				(max_width 2)
				(curved_edges yes)
				(filter_ratio 0.9)
				(enabled yes)
				(allow_two_segments yes)
				(prefer_zone_connections yes)
			)
		)
		(pad "2" smd roundrect
			(at 0.48 0 270)
			(size 0.59 0.64)
			(layers "F.Cu" "F.Mask" "F.Paste")
			(roundrect_rratio 0.25)
			(net 2 "+3V3")
			(pintype "passive")
			(teardrops
				(best_length_ratio 0.2)
				(max_length 1)
				(best_width_ratio 0.9)
				(max_width 2)
				(curved_edges yes)
				(filter_ratio 0.9)
				(enabled yes)
				(allow_two_segments yes)
				(prefer_zone_connections yes)
			)
		)
	)
	(footprint "antmicro-footprints:SOT-323"
		(layer "F.Cu")
		(at 261.35 92.41 90)
		(property "Reference" "Q6"
			(at -0.75 -1.45 90)
			(layer "F.SilkS")
			(effects
				(font
					(size 0.7 0.7)
					(thickness 0.15)
				)
				(justify left bottom)
			)
		)
		(property "Value" "BSS84AKW"
			(at 0 2.749 90)
			(layer "F.Fab")
			(effects
				(font
					(size 0.7 0.7)
					(thickness 0.15)
				)
				(justify left bottom)
			)
		)
		(property "Datasheet" "https://assets.nexperia.com/documents/data-sheet/BSS84AKW.pdf"
			(at 0 0 90)
			(layer "F.Fab")
			(hide yes)
			(effects
				(font
					(size 1.27 1.27)
					(thickness 0.15)
				)
			)
		)
		(property "Author" "Antmicro"
			(at 353.76 -168.94 0)
			(layer "F.Fab")
			(hide yes)
			(effects
				(font
					(size 1 1)
					(thickness 0.15)
				)
			)
		)
		(property "License" "Apache-2.0"
			(at 353.76 -168.94 0)
			(layer "F.Fab")
			(hide yes)
			(effects
				(font
					(size 1 1)
					(thickness 0.15)
				)
			)
		)
		(property "MPN" "BSS84AKW,115"
			(at 353.76 -168.94 0)
			(layer "F.Fab")
			(hide yes)
			(effects
				(font
					(size 1 1)
					(thickness 0.15)
				)
			)
		)
		(property "Manufacturer" "Nexperia"
			(at 353.76 -168.94 0)
			(layer "F.Fab")
			(hide yes)
			(effects
				(font
					(size 1 1)
					(thickness 0.15)
				)
			)
		)
		(sheetname "Misc")
		(sheetfile "misc.kicad_sch")
		(attr smd)
		(fp_line
			(start 0.8 -1.2)
			(end 0.8 -0.902)
			(stroke
				(width 0.15)
				(type solid)
			)
			(layer "F.SilkS")
		)
		(fp_line
			(start 0.498 -1.2)
			(end 0.8 -1.2)
			(stroke
				(width 0.15)
				(type solid)
			)
			(layer "F.SilkS")
		)
		(fp_line
			(start -0.402 -1.2)
			(end -0.802 -1.2)
			(stroke
				(width 0.15)
				(type solid)
			)
			(layer "F.SilkS")
		)
		(fp_line
			(start -0.802 -1.2)
			(end -0.802 -1.05)
			(stroke
				(width 0.15)
				(type solid)
			)
			(layer "F.SilkS")
		)
		(fp_line
			(start -0.802 1.05)
			(end -0.802 1.199)
			(stroke
				(width 0.15)
				(type solid)
			)
			(layer "F.SilkS")
		)
		(fp_line
			(start 0.8 1.199)
			(end 0.8 0.9)
			(stroke
				(width 0.15)
				(type solid)
			)
			(layer "F.SilkS")
		)
		(fp_line
			(start 0.498 1.199)
			(end 0.8 1.199)
			(stroke
				(width 0.15)
				(type solid)
			)
			(layer "F.SilkS")
		)
		(fp_line
			(start -0.802 1.199)
			(end -0.5 1.199)
			(stroke
				(width 0.15)
				(type solid)
			)
			(layer "F.SilkS")
		)
		(fp_circle
			(center -1.05 -1.156824)
			(end -1 -1.129824)
			(stroke
				(width 0.15)
				(type solid)
			)
			(fill no)
			(layer "F.SilkS")
		)
		(fp_rect
			(start -1.35 -1.35)
			(end 1.35 1.35)
			(stroke
				(width 0.05)
				(type solid)
			)
			(fill no)
			(layer "F.CrtYd")
		)
		(fp_line
			(start 0.675 -1.101)
			(end 0.675 1.1)
			(stroke
				(width 0.15)
				(type solid)
			)
			(layer "F.Fab")
		)
		(fp_line
			(start -0.677 -1.101)
			(end 0.675 -1.101)
			(stroke
				(width 0.15)
				(type solid)
			)
			(layer "F.Fab")
		)
		(fp_line
			(start -0.677 -1.101)
			(end -0.677 1.1)
			(stroke
				(width 0.15)
				(type solid)
			)
			(layer "F.Fab")
		)
		(fp_line
			(start -0.677 1.1)
			(end 0.675 1.1)
			(stroke
				(width 0.15)
				(type solid)
			)
			(layer "F.Fab")
		)
		(pad "1" smd rect
			(at -0.927 -0.652 90)
			(size 0.55 0.6)
			(layers "F.Cu" "F.Mask" "F.Paste")
			(net 538 "Net-(Q5-D)")
			(pinfunction "G")
			(pintype "bidirectional")
			(teardrops
				(best_length_ratio 0.2)
				(max_length 1)
				(best_width_ratio 0.9)
				(max_width 2)
				(curved_edges yes)
				(filter_ratio 0.9)
				(enabled yes)
				(allow_two_segments yes)
				(prefer_zone_connections yes)
			)
		)
		(pad "2" smd rect
			(at -0.927 0.65 90)
			(size 0.55 0.6)
			(layers "F.Cu" "F.Mask" "F.Paste")
			(net 2 "+3V3")
			(pinfunction "S")
			(pintype "bidirectional")
			(teardrops
				(best_length_ratio 0.2)
				(max_length 1)
				(best_width_ratio 0.9)
				(max_width 2)
				(curved_edges yes)
				(filter_ratio 0.9)
				(enabled yes)
				(allow_two_segments yes)
				(prefer_zone_connections yes)
			)
		)
		(pad "3" smd rect
			(at 0.925 0 90)
			(size 0.55 0.6)
			(layers "F.Cu" "F.Mask" "F.Paste")
			(net 80 "Net-(Q6-D)")
			(pinfunction "D")
			(pintype "bidirectional")
			(teardrops
				(best_length_ratio 0.2)
				(max_length 1)
				(best_width_ratio 0.9)
				(max_width 2)
				(curved_edges yes)
				(filter_ratio 0.9)
				(enabled yes)
				(allow_two_segments yes)
				(prefer_zone_connections yes)
			)
		)
	)
)
